# T6G (Grand Teton) — schematic netlist excerpt (pin names and nets, part order shuffled) for the footprints in the layout excerpt that follows; sources: Cadence DE-HDL packaged netlist, KiCad conversion of 04192023_DAF0TMB3IC0_F0TG_MB_C_brd_V02_OCP.brd

C1344  Q_CAP  100PF 50V 5% EMPTY  pkg 0402  page 257 : A = P12V_AUX_ADC_MAM ; B = GND
PR3992  Q_RES  0 5% CHIP  pkg 0402LF  page 264 : A = HSC_D_OC_3 ; B = HSC_D_OC_R

(kicad_pcb
	(version 20260206)
	(generator "pcbnew")
	(generator_version "10.0")
	(general
		(thickness 1.6)
		(legacy_teardrops no)
	)
	(paper "A4")
	(title_block
		(title "04192023_DAF0TMB3IC0_F0TG_MB_C_brd_V02_OCP.brd")
		(comment 1 "Grand Teton / footprints 270-271 of 8354")
	)
	(layers
		(0 "F.Cu" signal "TOP")
		(4 "In1.Cu" signal "GND")
		(6 "In2.Cu" signal "IN1")
		(8 "In3.Cu" signal "GND1")
		(10 "In4.Cu" signal "IN2")
		(12 "In5.Cu" signal "GND2")
		(14 "In6.Cu" signal "IN3")
		(16 "In7.Cu" signal "GND3")
		(18 "In8.Cu" signal "VCC")
		(20 "In9.Cu" signal "VCC1")
		(22 "In10.Cu" signal "GND4")
		(24 "In11.Cu" signal "IN4")
		(26 "In12.Cu" signal "GND5")
		(28 "In13.Cu" signal "IN5")
		(30 "In14.Cu" signal "GND6")
		(32 "In15.Cu" signal "IN6")
		(34 "In16.Cu" signal "GND7")
		(2 "B.Cu" signal "BOTTOM")
		(9 "F.Adhes" user "F.Adhesive")
		(11 "B.Adhes" user "B.Adhesive")
		(13 "F.Paste" user "Package Geometry/Pastemask Top")
		(15 "B.Paste" user "Package Geometry/Pastemask Bottom")
		(5 "F.SilkS" user "Ref Des/Silkscreen Top")
		(7 "B.SilkS" user "Ref Des/Silkscreen Bottom")
		(1 "F.Mask" user "Board Geometry/Soldermask Top")
		(3 "B.Mask" user "Board Geometry/Soldermask Bottom")
		(17 "Dwgs.User" user "User.Drawings")
		(19 "Cmts.User" user "User.Comments")
		(21 "Eco1.User" user "User.Eco1")
		(23 "Eco2.User" user "User.Eco2")
		(25 "Edge.Cuts" user "Board Geometry/Outline")
		(27 "Margin" user)
		(31 "F.CrtYd" user "Package Geometry/Place Bound Top")
		(29 "B.CrtYd" user "Package Geometry/Place Bound Bottom")
		(35 "F.Fab" user "Ref Des/Assembly Top")
		(33 "B.Fab" user "Ref Des/Assembly Bottom")
	)
	(footprint ""
		(layer "F.Cu")
		(at 315.771022 -34.858706 180)
		(property "Reference" "C1344"
			(at 0 0 180)
			(layer "F.SilkS")
			(hide yes)
			(effects
				(font
					(size 1.27 1.27)
				)
			)
		)
		(property "Value" ""
			(at 0 0 180)
			(layer "F.Fab")
			(effects
				(font
					(size 1.27 1.27)
				)
			)
		)
		(duplicate_pad_numbers_are_jumpers no)
		(fp_line
			(start 0.7874 0.4064)
			(end -0.7874 0.4064)
			(stroke
				(width 0.1524)
				(type default)
			)
			(layer "F.SilkS")
		)
		(fp_line
			(start 0.7874 -0.4064)
			(end 0.7874 0.4064)
			(stroke
				(width 0.1524)
				(type default)
			)
			(layer "F.SilkS")
		)
		(fp_line
			(start -0.7874 0.4064)
			(end -0.7874 -0.4064)
			(stroke
				(width 0.1524)
				(type default)
			)
			(layer "F.SilkS")
		)
		(fp_line
			(start -0.7874 -0.4064)
			(end 0.7874 -0.4064)
			(stroke
				(width 0.1524)
				(type default)
			)
			(layer "F.SilkS")
		)
		(fp_line
			(start 0.67945 0.3048)
			(end 0.120396 0.3048)
			(stroke
				(width 0.1)
				(type default)
			)
			(layer "F.Fab")
		)
		(fp_line
			(start 0.67945 -0.3048)
			(end 0.67945 0.3048)
			(stroke
				(width 0.1)
				(type default)
			)
			(layer "F.Fab")
		)
		(fp_line
			(start 0.12065 -0.2794)
			(end 0.12065 -0.3048)
			(stroke
				(width 0.1)
				(type default)
			)
			(layer "F.Fab")
		)
		(fp_line
			(start 0.12065 -0.3048)
			(end 0.67945 -0.3048)
			(stroke
				(width 0.1)
				(type default)
			)
			(layer "F.Fab")
		)
		(fp_line
			(start 0.120396 0.3048)
			(end 0.120396 0.2794)
			(stroke
				(width 0.1)
				(type default)
			)
			(layer "F.Fab")
		)
		(fp_line
			(start 0.120396 0.2794)
			(end -0.12065 0.2794)
			(stroke
				(width 0.1)
				(type default)
			)
			(layer "F.Fab")
		)
		(fp_line
			(start -0.12065 0.3048)
			(end -0.67945 0.3048)
			(stroke
				(width 0.1)
				(type default)
			)
			(layer "F.Fab")
		)
		(fp_line
			(start -0.12065 0.2794)
			(end -0.12065 0.3048)
			(stroke
				(width 0.1)
				(type default)
			)
			(layer "F.Fab")
		)
		(fp_line
			(start -0.12065 -0.2794)
			(end 0.12065 -0.2794)
			(stroke
				(width 0.1)
				(type default)
			)
			(layer "F.Fab")
		)
		(fp_line
			(start -0.12065 -0.305054)
			(end -0.12065 -0.2794)
			(stroke
				(width 0.1)
				(type default)
			)
			(layer "F.Fab")
		)
		(fp_line
			(start -0.67945 0.3048)
			(end -0.67945 -0.305054)
			(stroke
				(width 0.1)
				(type default)
			)
			(layer "F.Fab")
		)
		(fp_line
			(start -0.67945 -0.305054)
			(end -0.12065 -0.305054)
			(stroke
				(width 0.1)
				(type default)
			)
			(layer "F.Fab")
		)
		(pad "1" smd circle
			(at -0.40005 0 180)
			(size 0 0)
			(layers "F.Cu" "F.Mask" "F.Paste")
			(net "P12V_AUX_ADC_MAM")
		)
		(pad "2" smd circle
			(at 0.40005 0 180)
			(size 0 0)
			(layers "F.Cu" "F.Mask" "F.Paste")
			(net "GND")
		)
	)
	(footprint ""
		(layer "F.Cu")
		(at 226.0981 -399.956782)
		(property "Reference" "PR3992"
			(at 0 0 0)
			(layer "F.SilkS")
			(hide yes)
			(effects
				(font
					(size 1.27 1.27)
				)
			)
		)
		(property "Value" ""
			(at 0 0 0)
			(layer "F.Fab")
			(effects
				(font
					(size 1.27 1.27)
				)
			)
		)
		(duplicate_pad_numbers_are_jumpers no)
		(fp_line
			(start -0.7874 -0.4064)
			(end 0.7874 -0.4064)
			(stroke
				(width 0.1524)
				(type default)
			)
			(layer "F.SilkS")
		)
		(fp_line
			(start -0.7874 0.4064)
			(end -0.7874 -0.4064)
			(stroke
				(width 0.1524)
				(type default)
			)
			(layer "F.SilkS")
		)
		(fp_line
			(start 0.7874 -0.4064)
			(end 0.7874 0.4064)
			(stroke
				(width 0.1524)
				(type default)
			)
			(layer "F.SilkS")
		)
		(fp_line
			(start 0.7874 0.4064)
			(end -0.7874 0.4064)
			(stroke
				(width 0.1524)
				(type default)
			)
			(layer "F.SilkS")
		)
		(fp_line
			(start -0.67945 -0.305054)
			(end -0.12065 -0.305054)
			(stroke
				(width 0.1)
				(type default)
			)
			(layer "F.Fab")
		)
		(fp_line
			(start -0.67945 0.3048)
			(end -0.67945 -0.305054)
			(stroke
				(width 0.1)
				(type default)
			)
			(layer "F.Fab")
		)
		(fp_line
			(start -0.12065 -0.305054)
			(end -0.12065 -0.2794)
			(stroke
				(width 0.1)
				(type default)
			)
			(layer "F.Fab")
		)
		(fp_line
			(start -0.12065 -0.2794)
			(end 0.12065 -0.2794)
			(stroke
				(width 0.1)
				(type default)
			)
			(layer "F.Fab")
		)
		(fp_line
			(start -0.12065 0.2794)
			(end -0.12065 0.3048)
			(stroke
				(width 0.1)
				(type default)
			)
			(layer "F.Fab")
		)
		(fp_line
			(start -0.12065 0.3048)
			(end -0.67945 0.3048)
			(stroke
				(width 0.1)
				(type default)
			)
			(layer "F.Fab")
		)
		(fp_line
			(start 0.120396 0.2794)
			(end -0.12065 0.2794)
			(stroke
				(width 0.1)
				(type default)
			)
			(layer "F.Fab")
		)
		(fp_line
			(start 0.120396 0.3048)
			(end 0.120396 0.2794)
			(stroke
				(width 0.1)
				(type default)
			)
			(layer "F.Fab")
		)
		(fp_line
			(start 0.12065 -0.3048)
			(end 0.67945 -0.3048)
			(stroke
				(width 0.1)
				(type default)
			)
			(layer "F.Fab")
		)
		(fp_line
			(start 0.12065 -0.2794)
			(end 0.12065 -0.3048)
			(stroke
				(width 0.1)
				(type default)
			)
			(layer "F.Fab")
		)
		(fp_line
			(start 0.67945 -0.3048)
			(end 0.67945 0.3048)
			(stroke
				(width 0.1)
				(type default)
			)
			(layer "F.Fab")
		)
		(fp_line
			(start 0.67945 0.3048)
			(end 0.120396 0.3048)
			(stroke
				(width 0.1)
				(type default)
			)
			(layer "F.Fab")
		)
		(pad "1" smd circle
			(at -0.40005 0)
			(size 0 0)
			(layers "F.Cu" "F.Mask" "F.Paste")
			(net "HSC_D_OC_3")
		)
		(pad "2" smd circle
			(at 0.40005 0)
			(size 0 0)
			(layers "F.Cu" "F.Mask" "F.Paste")
			(net "HSC_D_OC_R")
		)
	)
)
